# SCM (Grand Teton) — schematic netlist excerpt (pin names and nets, part order shuffled) for the footprints in the layout excerpt that follows; sources: Cadence DE-HDL packaged netlist, KiCad conversion of 12092022_DA0F0TMDCD0_F0T_Management_Board_D_brd_V3_OCP.brd

L12  Q_INDUCTOR  BLM18PG121SN1D/2000MA IND  pkg SMLF  page 16 : \1\ = P3V3_AUX ; \2\ = A_BMC_ADCAV33
R338  Q_RES  120 1% CHIP  pkg 0402LF  page 20 : A = GND ; B = M_BMC_DDR4_MA<12>

(kicad_pcb
	(version 20260206)
	(generator "pcbnew")
	(generator_version "10.0")
	(general
		(thickness 1.6)
		(legacy_teardrops no)
	)
	(paper "A4")
	(title_block
		(title "12092022_DA0F0TMDCD0_F0T_Management_Board_D_brd_V3_OCP.brd")
		(comment 1 "Grand Teton / footprints 1434-1435 of 1440")
	)
	(layers
		(0 "F.Cu" signal "TOP")
		(4 "In1.Cu" signal "GND")
		(6 "In2.Cu" signal "IN1")
		(8 "In3.Cu" signal "GND1")
		(10 "In4.Cu" signal "IN2")
		(12 "In5.Cu" signal "VCC")
		(14 "In6.Cu" signal "VCC1")
		(16 "In7.Cu" signal "IN3")
		(18 "In8.Cu" signal "GND2")
		(20 "In9.Cu" signal "IN4")
		(22 "In10.Cu" signal "GND3")
		(2 "B.Cu" signal "BOTTOM")
		(9 "F.Adhes" user "F.Adhesive")
		(11 "B.Adhes" user "B.Adhesive")
		(13 "F.Paste" user "Package Geometry/Pastemask Top")
		(15 "B.Paste" user "Package Geometry/Pastemask Bottom")
		(5 "F.SilkS" user "Ref Des/Silkscreen Top")
		(7 "B.SilkS" user "Ref Des/Silkscreen Bottom")
		(1 "F.Mask" user "Board Geometry/Soldermask Top")
		(3 "B.Mask" user "Board Geometry/Soldermask Bottom")
		(17 "Dwgs.User" user "User.Drawings")
		(19 "Cmts.User" user "User.Comments")
		(21 "Eco1.User" user "User.Eco1")
		(23 "Eco2.User" user "User.Eco2")
		(25 "Edge.Cuts" user "Board Geometry/Outline")
		(27 "Margin" user)
		(31 "F.CrtYd" user "Package Geometry/Place Bound Top")
		(29 "B.CrtYd" user "Package Geometry/Place Bound Bottom")
		(35 "F.Fab" user "Ref Des/Assembly Top")
		(33 "B.Fab" user "Ref Des/Assembly Bottom")
	)
	(footprint ""
		(layer "B.Cu")
		(at 83.16722 -45.570394)
		(property "Reference" "R338"
			(at 0 0 0)
			(layer "B.SilkS")
			(hide yes)
			(effects
				(font
					(size 1.27 1.27)
				)
				(justify mirror)
			)
		)
		(property "Value" ""
			(at 0 0 0)
			(layer "B.Fab")
			(effects
				(font
					(size 1.27 1.27)
				)
				(justify mirror)
			)
		)
		(duplicate_pad_numbers_are_jumpers no)
		(fp_line
			(start -0.7874 -0.4064)
			(end -0.7874 0.4064)
			(stroke
				(width 0.1524)
				(type default)
			)
			(layer "B.SilkS")
		)
		(fp_line
			(start -0.7874 0.4064)
			(end 0.7874 0.4064)
			(stroke
				(width 0.1524)
				(type default)
			)
			(layer "B.SilkS")
		)
		(fp_line
			(start 0.7874 -0.4064)
			(end -0.7874 -0.4064)
			(stroke
				(width 0.1524)
				(type default)
			)
			(layer "B.SilkS")
		)
		(fp_line
			(start 0.7874 0.4064)
			(end 0.7874 -0.4064)
			(stroke
				(width 0.1524)
				(type default)
			)
			(layer "B.SilkS")
		)
		(fp_line
			(start -0.67945 -0.3048)
			(end -0.67945 0.3048)
			(stroke
				(width 0.1)
				(type default)
			)
			(layer "B.Fab")
		)
		(fp_line
			(start -0.67945 0.3048)
			(end -0.120396 0.3048)
			(stroke
				(width 0.1)
				(type default)
			)
			(layer "B.Fab")
		)
		(fp_line
			(start -0.12065 -0.3048)
			(end -0.67945 -0.3048)
			(stroke
				(width 0.1)
				(type default)
			)
			(layer "B.Fab")
		)
		(fp_line
			(start -0.12065 -0.2794)
			(end -0.12065 -0.3048)
			(stroke
				(width 0.1)
				(type default)
			)
			(layer "B.Fab")
		)
		(fp_line
			(start -0.120396 0.2794)
			(end 0.12065 0.2794)
			(stroke
				(width 0.1)
				(type default)
			)
			(layer "B.Fab")
		)
		(fp_line
			(start -0.120396 0.3048)
			(end -0.120396 0.2794)
			(stroke
				(width 0.1)
				(type default)
			)
			(layer "B.Fab")
		)
		(fp_line
			(start 0.12065 -0.305054)
			(end 0.12065 -0.2794)
			(stroke
				(width 0.1)
				(type default)
			)
			(layer "B.Fab")
		)
		(fp_line
			(start 0.12065 -0.2794)
			(end -0.12065 -0.2794)
			(stroke
				(width 0.1)
				(type default)
			)
			(layer "B.Fab")
		)
		(fp_line
			(start 0.12065 0.2794)
			(end 0.12065 0.3048)
			(stroke
				(width 0.1)
				(type default)
			)
			(layer "B.Fab")
		)
		(fp_line
			(start 0.12065 0.3048)
			(end 0.67945 0.3048)
			(stroke
				(width 0.1)
				(type default)
			)
			(layer "B.Fab")
		)
		(fp_line
			(start 0.67945 -0.305054)
			(end 0.12065 -0.305054)
			(stroke
				(width 0.1)
				(type default)
			)
			(layer "B.Fab")
		)
		(fp_line
			(start 0.67945 0.3048)
			(end 0.67945 -0.305054)
			(stroke
				(width 0.1)
				(type default)
			)
			(layer "B.Fab")
		)
		(pad "1" smd circle
			(at 0.40005 0 180)
			(size 0 0)
			(layers "B.Cu" "B.Mask" "B.Paste")
			(net "GND")
		)
		(pad "2" smd circle
			(at -0.40005 0 180)
			(size 0 0)
			(layers "B.Cu" "B.Mask" "B.Paste")
			(net "M_BMC_DDR4_MA<12>")
		)
	)
	(footprint ""
		(layer "B.Cu")
		(at 42.4688 -59.2074 180)
		(property "Reference" "L12"
			(at 0 0 0)
			(layer "B.SilkS")
			(hide yes)
			(effects
				(font
					(size 1.27 1.27)
				)
				(justify mirror)
			)
		)
		(property "Value" ""
			(at 0 0 0)
			(layer "B.Fab")
			(effects
				(font
					(size 1.27 1.27)
				)
				(justify mirror)
			)
		)
		(duplicate_pad_numbers_are_jumpers no)
		(fp_line
			(start 1.27 0.5842)
			(end 1.27 -0.5842)
			(stroke
				(width 0.1524)
				(type default)
			)
			(layer "B.SilkS")
		)
		(fp_line
			(start 1.27 -0.5588)
			(end 1.27 -0.5842)
			(stroke
				(width 0.1524)
				(type default)
			)
			(layer "B.SilkS")
		)
		(fp_line
			(start 1.27 -0.5842)
			(end -1.27 -0.5842)
			(stroke
				(width 0.1524)
				(type default)
			)
			(layer "B.SilkS")
		)
		(fp_line
			(start 0.127 0.5842)
			(end 0.127 -0.5842)
			(stroke
				(width 0.1524)
				(type default)
			)
			(layer "B.SilkS")
		)
		(fp_line
			(start -0.127 0.5842)
			(end -0.127 -0.5842)
			(stroke
				(width 0.1524)
				(type default)
			)
			(layer "B.SilkS")
		)
		(fp_line
			(start -1.27 0.5842)
			(end 1.27 0.5842)
			(stroke
				(width 0.1524)
				(type default)
			)
			(layer "B.SilkS")
		)
		(fp_line
			(start -1.27 0.5842)
			(end -1.27 -0.5842)
			(stroke
				(width 0.1524)
				(type default)
			)
			(layer "B.SilkS")
		)
		(fp_line
			(start 1.194308 0.406654)
			(end 1.194308 -0.406654)
			(stroke
				(width 0.1)
				(type default)
			)
			(layer "B.Fab")
		)
		(fp_line
			(start 1.194308 -0.406654)
			(end 0.9144 -0.406654)
			(stroke
				(width 0.1)
				(type default)
			)
			(layer "B.Fab")
		)
		(fp_line
			(start 0.9144 0.508)
			(end 0.9144 0.406654)
			(stroke
				(width 0.1)
				(type default)
			)
			(layer "B.Fab")
		)
		(fp_line
			(start 0.9144 0.406654)
			(end 1.194308 0.406654)
			(stroke
				(width 0.1)
				(type default)
			)
			(layer "B.Fab")
		)
		(fp_line
			(start 0.9144 -0.406654)
			(end 0.9144 -0.508)
			(stroke
				(width 0.1)
				(type default)
			)
			(layer "B.Fab")
		)
		(fp_line
			(start 0.9144 -0.508)
			(end -0.9144 -0.508)
			(stroke
				(width 0.1)
				(type default)
			)
			(layer "B.Fab")
		)
		(fp_line
			(start -0.9144 0.508)
			(end 0.9144 0.508)
			(stroke
				(width 0.1)
				(type default)
			)
			(layer "B.Fab")
		)
		(fp_line
			(start -0.9144 0.4064)
			(end -0.9144 0.508)
			(stroke
				(width 0.1)
				(type default)
			)
			(layer "B.Fab")
		)
		(fp_line
			(start -0.9144 -0.406654)
			(end -1.1938 -0.406654)
			(stroke
				(width 0.1)
				(type default)
			)
			(layer "B.Fab")
		)
		(fp_line
			(start -0.9144 -0.508)
			(end -0.9144 -0.406654)
			(stroke
				(width 0.1)
				(type default)
			)
			(layer "B.Fab")
		)
		(fp_line
			(start -1.1938 0.4064)
			(end -0.9144 0.4064)
			(stroke
				(width 0.1)
				(type default)
			)
			(layer "B.Fab")
		)
		(fp_line
			(start -1.1938 -0.406654)
			(end -1.1938 0.4064)
			(stroke
				(width 0.1)
				(type default)
			)
			(layer "B.Fab")
		)
		(pad "1" smd rect
			(at 0.7366 0 90)
			(size 0.7112 0.8128)
			(layers "B.Cu" "B.Mask" "B.Paste")
			(net "P3V3_AUX")
		)
		(pad "2" smd rect
			(at -0.7366 0 90)
			(size 0.7112 0.8128)
			(layers "B.Cu" "B.Mask" "B.Paste")
			(net "A_BMC_ADCAV33")
		)
	)
)
